# T6G (Grand Teton) — schematic netlist excerpt (pin names and nets, part order shuffled) for the footprints in the layout excerpt that follows; sources: Cadence DE-HDL packaged netlist, KiCad conversion of 04192023_DAF0TMB3IC0_F0TG_MB_C_brd_V02_OCP.brd

C828  Q_CAP_DIFFBUS  DIFF BUS_0.22UF 6.3V 20% X6S  pkg C0201  page 65 : \1\ = P5E_CPU1_P0_TX_C_DN<4> ; \2\ = P5E_CPU1_P0_TX_DN<4>
R6789  Q_RES  1K 1% CHIP  pkg 0201LF  page 333 : A = U19_E2 ; B = GND
PR3838  Q_RES  100 1% EMPTY  pkg 0402LF  page 135 : A = P12V_OCP_SFF ; B = P12V_OCP_AVIN_PD_1
C941  Q_CAP_DIFFBUS  DIFF BUS_0.22UF 6.3V 20% X6S  pkg C0201  page 63 : \1\ = P5E_CPU0_P1_TX_C_DP<12> ; \2\ = P5E_CPU0_P1_TX_DP<12>

(kicad_pcb
	(version 20260206)
	(generator "pcbnew")
	(generator_version "10.0")
	(general
		(thickness 1.6)
		(legacy_teardrops no)
	)
	(paper "A4")
	(title_block
		(title "04192023_DAF0TMB3IC0_F0TG_MB_C_brd_V02_OCP.brd")
		(comment 1 "Grand Teton / footprints 1106-1109 of 8354")
	)
	(layers
		(0 "F.Cu" signal "TOP")
		(4 "In1.Cu" signal "GND")
		(6 "In2.Cu" signal "IN1")
		(8 "In3.Cu" signal "GND1")
		(10 "In4.Cu" signal "IN2")
		(12 "In5.Cu" signal "GND2")
		(14 "In6.Cu" signal "IN3")
		(16 "In7.Cu" signal "GND3")
		(18 "In8.Cu" signal "VCC")
		(20 "In9.Cu" signal "VCC1")
		(22 "In10.Cu" signal "GND4")
		(24 "In11.Cu" signal "IN4")
		(26 "In12.Cu" signal "GND5")
		(28 "In13.Cu" signal "IN5")
		(30 "In14.Cu" signal "GND6")
		(32 "In15.Cu" signal "IN6")
		(34 "In16.Cu" signal "GND7")
		(2 "B.Cu" signal "BOTTOM")
		(9 "F.Adhes" user "F.Adhesive")
		(11 "B.Adhes" user "B.Adhesive")
		(13 "F.Paste" user "Package Geometry/Pastemask Top")
		(15 "B.Paste" user "Package Geometry/Pastemask Bottom")
		(5 "F.SilkS" user "Ref Des/Silkscreen Top")
		(7 "B.SilkS" user "Ref Des/Silkscreen Bottom")
		(1 "F.Mask" user "Board Geometry/Soldermask Top")
		(3 "B.Mask" user "Board Geometry/Soldermask Bottom")
		(17 "Dwgs.User" user "User.Drawings")
		(19 "Cmts.User" user "User.Comments")
		(21 "Eco1.User" user "User.Eco1")
		(23 "Eco2.User" user "User.Eco2")
		(25 "Edge.Cuts" user "Board Geometry/Outline")
		(27 "Margin" user)
		(31 "F.CrtYd" user "Package Geometry/Place Bound Top")
		(29 "B.CrtYd" user "Package Geometry/Place Bound Bottom")
		(35 "F.Fab" user "Ref Des/Assembly Top")
		(33 "B.Fab" user "Ref Des/Assembly Bottom")
	)
	(footprint ""
		(layer "F.Cu")
		(at 49.009554 -375.49963 -90)
		(property "Reference" "C828"
			(at 0 0 270)
			(layer "F.SilkS")
			(hide yes)
			(effects
				(font
					(size 1.27 1.27)
				)
			)
		)
		(property "Value" ""
			(at 0 0 270)
			(layer "F.Fab")
			(effects
				(font
					(size 1.27 1.27)
				)
			)
		)
		(duplicate_pad_numbers_are_jumpers no)
		(fp_line
			(start -0.299974 0.150114)
			(end -0.299974 -0.150114)
			(stroke
				(width 0.1)
				(type default)
			)
			(layer "F.Fab")
		)
		(fp_line
			(start 0.299974 0.150114)
			(end -0.299974 0.150114)
			(stroke
				(width 0.1)
				(type default)
			)
			(layer "F.Fab")
		)
		(fp_line
			(start -0.299974 -0.150114)
			(end 0.299974 -0.150114)
			(stroke
				(width 0.1)
				(type default)
			)
			(layer "F.Fab")
		)
		(fp_line
			(start 0.299974 -0.150114)
			(end 0.299974 0.150114)
			(stroke
				(width 0.1)
				(type default)
			)
			(layer "F.Fab")
		)
		(pad "1" smd rect
			(at -0.2667 0 270)
			(size 0.3048 0.381)
			(layers "F.Cu" "F.Mask" "F.Paste")
			(net "P5E_CPU1_P0_TX_C_DN<4>")
		)
		(pad "2" smd rect
			(at 0.2667 0 270)
			(size 0.3048 0.381)
			(layers "F.Cu" "F.Mask" "F.Paste")
			(net "P5E_CPU1_P0_TX_DN<4>")
		)
	)
	(footprint ""
		(layer "F.Cu")
		(at 353.640644 -378.95403 -90)
		(property "Reference" "C941"
			(at 0 0 270)
			(layer "F.SilkS")
			(hide yes)
			(effects
				(font
					(size 1.27 1.27)
				)
			)
		)
		(property "Value" ""
			(at 0 0 270)
			(layer "F.Fab")
			(effects
				(font
					(size 1.27 1.27)
				)
			)
		)
		(duplicate_pad_numbers_are_jumpers no)
		(fp_line
			(start -0.299974 0.150114)
			(end -0.299974 -0.150114)
			(stroke
				(width 0.1)
				(type default)
			)
			(layer "F.Fab")
		)
		(fp_line
			(start 0.299974 0.150114)
			(end -0.299974 0.150114)
			(stroke
				(width 0.1)
				(type default)
			)
			(layer "F.Fab")
		)
		(fp_line
			(start -0.299974 -0.150114)
			(end 0.299974 -0.150114)
			(stroke
				(width 0.1)
				(type default)
			)
			(layer "F.Fab")
		)
		(fp_line
			(start 0.299974 -0.150114)
			(end 0.299974 0.150114)
			(stroke
				(width 0.1)
				(type default)
			)
			(layer "F.Fab")
		)
		(pad "1" smd rect
			(at -0.2667 0 270)
			(size 0.3048 0.381)
			(layers "F.Cu" "F.Mask" "F.Paste")
			(net "P5E_CPU0_P1_TX_C_DP<12>")
		)
		(pad "2" smd rect
			(at 0.2667 0 270)
			(size 0.3048 0.381)
			(layers "F.Cu" "F.Mask" "F.Paste")
			(net "P5E_CPU0_P1_TX_DP<12>")
		)
	)
	(footprint ""
		(layer "F.Cu")
		(at 109.332014 -405.633682 180)
		(property "Reference" "R6789"
			(at 0 0 180)
			(layer "F.SilkS")
			(hide yes)
			(effects
				(font
					(size 1.27 1.27)
				)
			)
		)
		(property "Value" ""
			(at 0 0 180)
			(layer "F.Fab")
			(effects
				(font
					(size 1.27 1.27)
				)
			)
		)
		(duplicate_pad_numbers_are_jumpers no)
		(fp_line
			(start 0.32512 0.175006)
			(end -0.32512 0.175006)
			(stroke
				(width 0.1)
				(type default)
			)
			(layer "F.Fab")
		)
		(fp_line
			(start 0.32512 -0.175006)
			(end 0.32512 0.175006)
			(stroke
				(width 0.1)
				(type default)
			)
			(layer "F.Fab")
		)
		(fp_line
			(start -0.32512 0.175006)
			(end -0.32512 -0.175006)
			(stroke
				(width 0.1)
				(type default)
			)
			(layer "F.Fab")
		)
		(fp_line
			(start -0.32512 -0.175006)
			(end 0.32512 -0.175006)
			(stroke
				(width 0.1)
				(type default)
			)
			(layer "F.Fab")
		)
		(pad "1" smd rect
			(at -0.2667 0 180)
			(size 0.3048 0.381)
			(layers "F.Cu" "F.Mask" "F.Paste")
			(net "U19_E2")
		)
		(pad "2" smd rect
			(at 0.2667 0)
			(size 0.3048 0.381)
			(layers "F.Cu" "F.Mask" "F.Paste")
			(net "GND")
		)
	)
	(footprint ""
		(layer "F.Cu")
		(at 440.592972 -22.816058 180)
		(property "Reference" "PR3838"
			(at 0 0 180)
			(layer "F.SilkS")
			(hide yes)
			(effects
				(font
					(size 1.27 1.27)
				)
			)
		)
		(property "Value" ""
			(at 0 0 180)
			(layer "F.Fab")
			(effects
				(font
					(size 1.27 1.27)
				)
			)
		)
		(duplicate_pad_numbers_are_jumpers no)
		(fp_line
			(start 0.7874 0.4064)
			(end -0.7874 0.4064)
			(stroke
				(width 0.1524)
				(type default)
			)
			(layer "F.SilkS")
		)
		(fp_line
			(start 0.7874 -0.4064)
			(end 0.7874 0.4064)
			(stroke
				(width 0.1524)
				(type default)
			)
			(layer "F.SilkS")
		)
		(fp_line
			(start -0.7874 0.4064)
			(end -0.7874 -0.4064)
			(stroke
				(width 0.1524)
				(type default)
			)
			(layer "F.SilkS")
		)
		(fp_line
			(start -0.7874 -0.4064)
			(end 0.7874 -0.4064)
			(stroke
				(width 0.1524)
				(type default)
			)
			(layer "F.SilkS")
		)
		(fp_line
			(start 0.67945 0.3048)
			(end 0.120396 0.3048)
			(stroke
				(width 0.1)
				(type default)
			)
			(layer "F.Fab")
		)
		(fp_line
			(start 0.67945 -0.3048)
			(end 0.67945 0.3048)
			(stroke
				(width 0.1)
				(type default)
			)
			(layer "F.Fab")
		)
		(fp_line
			(start 0.12065 -0.2794)
			(end 0.12065 -0.3048)
			(stroke
				(width 0.1)
				(type default)
			)
			(layer "F.Fab")
		)
		(fp_line
			(start 0.12065 -0.3048)
			(end 0.67945 -0.3048)
			(stroke
				(width 0.1)
				(type default)
			)
			(layer "F.Fab")
		)
		(fp_line
			(start 0.120396 0.3048)
			(end 0.120396 0.2794)
			(stroke
				(width 0.1)
				(type default)
			)
			(layer "F.Fab")
		)
		(fp_line
			(start 0.120396 0.2794)
			(end -0.12065 0.2794)
			(stroke
				(width 0.1)
				(type default)
			)
			(layer "F.Fab")
		)
		(fp_line
			(start -0.12065 0.3048)
			(end -0.67945 0.3048)
			(stroke
				(width 0.1)
				(type default)
			)
			(layer "F.Fab")
		)
		(fp_line
			(start -0.12065 0.2794)
			(end -0.12065 0.3048)
			(stroke
				(width 0.1)
				(type default)
			)
			(layer "F.Fab")
		)
		(fp_line
			(start -0.12065 -0.2794)
			(end 0.12065 -0.2794)
			(stroke
				(width 0.1)
				(type default)
			)
			(layer "F.Fab")
		)
		(fp_line
			(start -0.12065 -0.305054)
			(end -0.12065 -0.2794)
			(stroke
				(width 0.1)
				(type default)
			)
			(layer "F.Fab")
		)
		(fp_line
			(start -0.67945 0.3048)
			(end -0.67945 -0.305054)
			(stroke
				(width 0.1)
				(type default)
			)
			(layer "F.Fab")
		)
		(fp_line
			(start -0.67945 -0.305054)
			(end -0.12065 -0.305054)
			(stroke
				(width 0.1)
				(type default)
			)
			(layer "F.Fab")
		)
		(pad "1" smd circle
			(at -0.40005 0 180)
			(size 0 0)
			(layers "F.Cu" "F.Mask" "F.Paste")
			(net "P12V_OCP_SFF")
		)
		(pad "2" smd circle
			(at 0.40005 0 180)
			(size 0 0)
			(layers "F.Cu" "F.Mask" "F.Paste")
			(net "P12V_OCP_AVIN_PD_1")
		)
	)
)
